# S9S_MB_2U (Grand Teton) — schematic netlist excerpt (pin names and nets, part order shuffled) for the footprints in the layout excerpt that follows; sources: Cadence DE-HDL packaged netlist, KiCad conversion of 03242023_DA0F0TMBIJ0_F0T_Motherboard_J_brd_V01_OCP.brd

PC2001  Q_CAP  0.022UF 16V 10% X7R  pkg 0402  page 281 : A = PVPP_HBM_CPU0_REF ; B = GND
C1033  Q_CAP  22UF 4V 20% X6S  pkg C0402  page 74 : A = PVCCIN_CPU0 ; B = GND
C869  Q_CAP_DIFFBUS  DIFF BUS_0.22UF 6.3V 20% X6S  pkg C0201  page 174 : \1\ = P5E_CPU0_PE1_TX_C_DP<0> ; \2\ = P5E_CPU0_PE1_TX_DP<0>

(kicad_pcb
	(version 20260206)
	(generator "pcbnew")
	(generator_version "10.0")
	(general
		(thickness 1.6)
		(legacy_teardrops no)
	)
	(paper "A4")
	(title_block
		(title "03242023_DA0F0TMBIJ0_F0T_Motherboard_J_brd_V01_OCP.brd")
		(comment 1 "Grand Teton / footprints 3328-3330 of 6105")
	)
	(layers
		(0 "F.Cu" signal "TOP")
		(4 "In1.Cu" signal "GND")
		(6 "In2.Cu" signal "IN1")
		(8 "In3.Cu" signal "GND1")
		(10 "In4.Cu" signal "IN2")
		(12 "In5.Cu" signal "GND2")
		(14 "In6.Cu" signal "IN3")
		(16 "In7.Cu" signal "GND3")
		(18 "In8.Cu" signal "VCC")
		(20 "In9.Cu" signal "VCC1")
		(22 "In10.Cu" signal "GND4")
		(24 "In11.Cu" signal "IN4")
		(26 "In12.Cu" signal "GND5")
		(28 "In13.Cu" signal "IN5")
		(30 "In14.Cu" signal "GND6")
		(32 "In15.Cu" signal "IN6")
		(34 "In16.Cu" signal "GND7")
		(2 "B.Cu" signal "BOTTOM")
		(9 "F.Adhes" user "F.Adhesive")
		(11 "B.Adhes" user "B.Adhesive")
		(13 "F.Paste" user "Package Geometry/Pastemask Top")
		(15 "B.Paste" user "Package Geometry/Pastemask Bottom")
		(5 "F.SilkS" user "Ref Des/Silkscreen Top")
		(7 "B.SilkS" user "Ref Des/Silkscreen Bottom")
		(1 "F.Mask" user "Board Geometry/Soldermask Top")
		(3 "B.Mask" user "Board Geometry/Soldermask Bottom")
		(17 "Dwgs.User" user "User.Drawings")
		(19 "Cmts.User" user "User.Comments")
		(21 "Eco1.User" user "User.Eco1")
		(23 "Eco2.User" user "User.Eco2")
		(25 "Edge.Cuts" user "Board Geometry/Outline")
		(27 "Margin" user)
		(31 "F.CrtYd" user "Package Geometry/Place Bound Top")
		(29 "B.CrtYd" user "Package Geometry/Place Bound Bottom")
		(35 "F.Fab" user "Ref Des/Assembly Top")
		(33 "B.Fab" user "Ref Des/Assembly Bottom")
	)
	(footprint ""
		(layer "F.Cu")
		(at 368.915188 -360.043222 90)
		(property "Reference" "PC2001"
			(at 0 0 90)
			(layer "F.SilkS")
			(hide yes)
			(effects
				(font
					(size 1.27 1.27)
				)
			)
		)
		(property "Value" ""
			(at 0 0 90)
			(layer "F.Fab")
			(effects
				(font
					(size 1.27 1.27)
				)
			)
		)
		(duplicate_pad_numbers_are_jumpers no)
		(fp_line
			(start 0.7874 -0.4064)
			(end 0.7874 0.4064)
			(stroke
				(width 0.1524)
				(type default)
			)
			(layer "F.SilkS")
		)
		(fp_line
			(start -0.7874 -0.4064)
			(end 0.7874 -0.4064)
			(stroke
				(width 0.1524)
				(type default)
			)
			(layer "F.SilkS")
		)
		(fp_line
			(start 0.7874 0.4064)
			(end -0.7874 0.4064)
			(stroke
				(width 0.1524)
				(type default)
			)
			(layer "F.SilkS")
		)
		(fp_line
			(start -0.7874 0.4064)
			(end -0.7874 -0.4064)
			(stroke
				(width 0.1524)
				(type default)
			)
			(layer "F.SilkS")
		)
		(fp_line
			(start -0.12065 -0.305054)
			(end -0.12065 -0.2794)
			(stroke
				(width 0.1)
				(type default)
			)
			(layer "F.Fab")
		)
		(fp_line
			(start -0.67945 -0.305054)
			(end -0.12065 -0.305054)
			(stroke
				(width 0.1)
				(type default)
			)
			(layer "F.Fab")
		)
		(fp_line
			(start 0.67945 -0.3048)
			(end 0.67945 0.3048)
			(stroke
				(width 0.1)
				(type default)
			)
			(layer "F.Fab")
		)
		(fp_line
			(start 0.12065 -0.3048)
			(end 0.67945 -0.3048)
			(stroke
				(width 0.1)
				(type default)
			)
			(layer "F.Fab")
		)
		(fp_line
			(start 0.12065 -0.2794)
			(end 0.12065 -0.3048)
			(stroke
				(width 0.1)
				(type default)
			)
			(layer "F.Fab")
		)
		(fp_line
			(start -0.12065 -0.2794)
			(end 0.12065 -0.2794)
			(stroke
				(width 0.1)
				(type default)
			)
			(layer "F.Fab")
		)
		(fp_line
			(start 0.120396 0.2794)
			(end -0.12065 0.2794)
			(stroke
				(width 0.1)
				(type default)
			)
			(layer "F.Fab")
		)
		(fp_line
			(start -0.12065 0.2794)
			(end -0.12065 0.3048)
			(stroke
				(width 0.1)
				(type default)
			)
			(layer "F.Fab")
		)
		(fp_line
			(start 0.67945 0.3048)
			(end 0.120396 0.3048)
			(stroke
				(width 0.1)
				(type default)
			)
			(layer "F.Fab")
		)
		(fp_line
			(start 0.120396 0.3048)
			(end 0.120396 0.2794)
			(stroke
				(width 0.1)
				(type default)
			)
			(layer "F.Fab")
		)
		(fp_line
			(start -0.12065 0.3048)
			(end -0.67945 0.3048)
			(stroke
				(width 0.1)
				(type default)
			)
			(layer "F.Fab")
		)
		(fp_line
			(start -0.67945 0.3048)
			(end -0.67945 -0.305054)
			(stroke
				(width 0.1)
				(type default)
			)
			(layer "F.Fab")
		)
		(pad "1" smd circle
			(at -0.40005 0 90)
			(size 0 0)
			(layers "F.Cu" "F.Mask" "F.Paste")
			(net "PVPP_HBM_CPU0_REF")
		)
		(pad "2" smd circle
			(at 0.40005 0 90)
			(size 0 0)
			(layers "F.Cu" "F.Mask" "F.Paste")
			(net "GND")
		)
	)
	(footprint ""
		(layer "F.Cu")
		(at 432.265836 -17.612614 90)
		(property "Reference" "C869"
			(at 0 0 90)
			(layer "F.SilkS")
			(hide yes)
			(effects
				(font
					(size 1.27 1.27)
				)
			)
		)
		(property "Value" ""
			(at 0 0 90)
			(layer "F.Fab")
			(effects
				(font
					(size 1.27 1.27)
				)
			)
		)
		(duplicate_pad_numbers_are_jumpers no)
		(fp_line
			(start 0.299974 -0.150114)
			(end 0.299974 0.150114)
			(stroke
				(width 0.1)
				(type default)
			)
			(layer "F.Fab")
		)
		(fp_line
			(start -0.299974 -0.150114)
			(end 0.299974 -0.150114)
			(stroke
				(width 0.1)
				(type default)
			)
			(layer "F.Fab")
		)
		(fp_line
			(start 0.299974 0.150114)
			(end -0.299974 0.150114)
			(stroke
				(width 0.1)
				(type default)
			)
			(layer "F.Fab")
		)
		(fp_line
			(start -0.299974 0.150114)
			(end -0.299974 -0.150114)
			(stroke
				(width 0.1)
				(type default)
			)
			(layer "F.Fab")
		)
		(pad "1" smd rect
			(at -0.2667 0 90)
			(size 0.3048 0.381)
			(layers "F.Cu" "F.Mask" "F.Paste")
			(net "P5E_CPU0_PE1_TX_C_DP<0>")
		)
		(pad "2" smd rect
			(at 0.2667 0 90)
			(size 0.3048 0.381)
			(layers "F.Cu" "F.Mask" "F.Paste")
			(net "P5E_CPU0_PE1_TX_DP<0>")
		)
	)
	(footprint ""
		(layer "F.Cu")
		(at 366.48263 -241.976656 -90)
		(property "Reference" "C1033"
			(at 0 0 270)
			(layer "F.SilkS")
			(hide yes)
			(effects
				(font
					(size 1.27 1.27)
				)
			)
		)
		(property "Value" ""
			(at 0 0 270)
			(layer "F.Fab")
			(effects
				(font
					(size 1.27 1.27)
				)
			)
		)
		(duplicate_pad_numbers_are_jumpers no)
		(fp_line
			(start -0.7874 0.4064)
			(end -0.7874 -0.4064)
			(stroke
				(width 0.1524)
				(type default)
			)
			(layer "F.SilkS")
		)
		(fp_line
			(start 0.7874 0.4064)
			(end -0.7874 0.4064)
			(stroke
				(width 0.1524)
				(type default)
			)
			(layer "F.SilkS")
		)
		(fp_line
			(start -0.7874 -0.4064)
			(end 0.7874 -0.4064)
			(stroke
				(width 0.1524)
				(type default)
			)
			(layer "F.SilkS")
		)
		(fp_line
			(start 0.7874 -0.4064)
			(end 0.7874 0.4064)
			(stroke
				(width 0.1524)
				(type default)
			)
			(layer "F.SilkS")
		)
		(fp_line
			(start -0.67945 0.3048)
			(end -0.67945 -0.305054)
			(stroke
				(width 0.1)
				(type default)
			)
			(layer "F.Fab")
		)
		(fp_line
			(start -0.12065 0.3048)
			(end -0.67945 0.3048)
			(stroke
				(width 0.1)
				(type default)
			)
			(layer "F.Fab")
		)
		(fp_line
			(start 0.120396 0.3048)
			(end 0.120396 0.2794)
			(stroke
				(width 0.1)
				(type default)
			)
			(layer "F.Fab")
		)
		(fp_line
			(start 0.67945 0.3048)
			(end 0.120396 0.3048)
			(stroke
				(width 0.1)
				(type default)
			)
			(layer "F.Fab")
		)
		(fp_line
			(start -0.12065 0.2794)
			(end -0.12065 0.3048)
			(stroke
				(width 0.1)
				(type default)
			)
			(layer "F.Fab")
		)
		(fp_line
			(start 0.120396 0.2794)
			(end -0.12065 0.2794)
			(stroke
				(width 0.1)
				(type default)
			)
			(layer "F.Fab")
		)
		(fp_line
			(start -0.12065 -0.2794)
			(end 0.12065 -0.2794)
			(stroke
				(width 0.1)
				(type default)
			)
			(layer "F.Fab")
		)
		(fp_line
			(start 0.12065 -0.2794)
			(end 0.12065 -0.3048)
			(stroke
				(width 0.1)
				(type default)
			)
			(layer "F.Fab")
		)
		(fp_line
			(start 0.12065 -0.3048)
			(end 0.67945 -0.3048)
			(stroke
				(width 0.1)
				(type default)
			)
			(layer "F.Fab")
		)
		(fp_line
			(start 0.67945 -0.3048)
			(end 0.67945 0.3048)
			(stroke
				(width 0.1)
				(type default)
			)
			(layer "F.Fab")
		)
		(fp_line
			(start -0.67945 -0.305054)
			(end -0.12065 -0.305054)
			(stroke
				(width 0.1)
				(type default)
			)
			(layer "F.Fab")
		)
		(fp_line
			(start -0.12065 -0.305054)
			(end -0.12065 -0.2794)
			(stroke
				(width 0.1)
				(type default)
			)
			(layer "F.Fab")
		)
		(pad "1" smd circle
			(at -0.40005 0 270)
			(size 0 0)
			(layers "F.Cu" "F.Mask" "F.Paste")
			(net "PVCCIN_CPU0")
		)
		(pad "2" smd circle
			(at 0.40005 0 270)
			(size 0 0)
			(layers "F.Cu" "F.Mask" "F.Paste")
			(net "GND")
		)
	)
)
